# BASEBOARD_FAB2 (Tioga Pass) — schematic netlist excerpt (pin names and nets, part order shuffled) for the footprints in the layout excerpt that follows; sources: Cadence DE-HDL packaged netlist, KiCad conversion of Wiwynn_Tioga_Pass_MB.brd

C3N39  CAP  220PF 50V 10% X7R  pkg 0402LF  page 211 : A = VR_PVCCIO_CPU0_AVSP ; B = VSENSE_PVCCIO_CPU0_AVSN
FB2T3  HCB1608KF-800T30-GP  pkg DISCRET-G9  page 149 : \1\ = P3V3_STBY ; \2\ = VCC_ADCAV3V3
C22W6  SC22U16V5MX-4-GP  20%  pkg SMD-BCG5  page 233 : \1\ = VR_FET_SW_P12V_STBY_PVPP_GHJ ; \2\ = GND

(kicad_pcb
	(version 20260206)
	(generator "pcbnew")
	(generator_version "10.0")
	(general
		(thickness 1.6)
		(legacy_teardrops no)
	)
	(paper "A4")
	(title_block
		(title "Wiwynn_Tioga_Pass_MB.brd")
		(comment 1 "Tioga Pass / footprints 2503-2505 of 4770")
	)
	(layers
		(0 "F.Cu" signal "TOP")
		(4 "In1.Cu" signal "L2GND")
		(6 "In2.Cu" signal "L3")
		(8 "In3.Cu" signal "L4GND")
		(10 "In4.Cu" signal "L5")
		(12 "In5.Cu" signal "L6GND")
		(14 "In6.Cu" signal "L7VCC")
		(16 "In7.Cu" signal "L8VCC")
		(18 "In8.Cu" signal "L9GND")
		(20 "In9.Cu" signal "L10")
		(22 "In10.Cu" signal "L11GND")
		(24 "In11.Cu" signal "L12")
		(26 "In12.Cu" signal "L13GND")
		(2 "B.Cu" signal "BOTTOM")
		(9 "F.Adhes" user "F.Adhesive")
		(11 "B.Adhes" user "B.Adhesive")
		(13 "F.Paste" user "Package Geometry/Pastemask Top")
		(15 "B.Paste" user "Package Geometry/Pastemask Bottom")
		(5 "F.SilkS" user "Ref Des/Silkscreen Top")
		(7 "B.SilkS" user "Ref Des/Silkscreen Bottom")
		(1 "F.Mask" user "Board Geometry/Soldermask Top")
		(3 "B.Mask" user "Board Geometry/Soldermask Bottom")
		(17 "Dwgs.User" user "User.Drawings")
		(19 "Cmts.User" user "User.Comments")
		(21 "Eco1.User" user "User.Eco1")
		(23 "Eco2.User" user "User.Eco2")
		(25 "Edge.Cuts" user "Board Geometry/Outline")
		(27 "Margin" user)
		(31 "F.CrtYd" user "Package Geometry/Place Bound Top")
		(29 "B.CrtYd" user "Package Geometry/Place Bound Bottom")
		(35 "F.Fab" user "Ref Des/Assembly Top")
		(33 "B.Fab" user "Ref Des/Assembly Bottom")
	)
	(footprint ""
		(layer "B.Cu")
		(at 411.861 -23.0632 90)
		(property "Reference" "FB2T3"
			(at 0 0 90)
			(layer "B.SilkS")
			(hide yes)
			(effects
				(font
					(size 1.27 1.27)
				)
				(justify mirror)
			)
		)
		(property "Value" "*"
			(at -0.0254 -2.8829 90)
			(unlocked yes)
			(layer "B.Fab")
			(hide yes)
			(effects
				(font
					(size 1.27 1.016)
					(thickness 0.1524)
				)
				(justify mirror)
			)
		)
		(property "Device Type" "HCB1608KF-800T30-GP_DISCRET-G9A"
			(at -0.0254 -4.4069 90)
			(unlocked yes)
			(layer "B.Fab")
			(hide yes)
			(effects
				(font
					(size 1.27 1.016)
					(thickness 0.1524)
				)
				(justify mirror)
			)
		)
		(duplicate_pad_numbers_are_jumpers no)
		(fp_line
			(start -0.254 0)
			(end 0.254 0)
			(stroke
				(width 0.2032)
				(type default)
			)
			(layer "B.SilkS")
		)
		(fp_rect
			(start 0.5842 1.3335)
			(end -0.5842 -1.3335)
			(stroke
				(width 0)
				(type default)
			)
			(fill no)
			(layer "B.CrtYd")
		)
		(fp_rect
			(start 0.5842 1.3335)
			(end -0.5842 -1.3335)
			(stroke
				(width 0)
				(type default)
			)
			(fill no)
			(layer "B.Fab")
		)
		(pad "1" smd custom
			(at 0 -0.762 270)
			(size 0.2159 0.2159)
			(layers "B.Cu" "B.Mask" "B.Paste")
			(net "P3V3_STBY")
			(options
				(clearance outline)
				(anchor circle)
			)
			(primitives
				(gr_poly
					(pts
						(arc
							(start -0.3302 0.4318)
							(mid -0.402042 0.402042)
							(end -0.4318 0.3302)
						)
						(arc
							(start -0.4318 -0.3302)
							(mid -0.402042 -0.402042)
							(end -0.3302 -0.4318)
						)
						(arc
							(start 0.3302 -0.4318)
							(mid 0.402042 -0.402042)
							(end 0.4318 -0.3302)
						)
						(arc
							(start 0.4318 0.3302)
							(mid 0.402042 0.402042)
							(end 0.3302 0.4318)
						)
					)
					(width 0)
					(fill yes)
				)
			)
		)
		(pad "2" smd custom
			(at 0 0.762 270)
			(size 0.2159 0.2159)
			(layers "B.Cu" "B.Mask" "B.Paste")
			(net "VCC_ADCAV3V3")
			(options
				(clearance outline)
				(anchor circle)
			)
			(primitives
				(gr_poly
					(pts
						(arc
							(start -0.3302 0.4318)
							(mid -0.402042 0.402042)
							(end -0.4318 0.3302)
						)
						(arc
							(start -0.4318 -0.3302)
							(mid -0.402042 -0.402042)
							(end -0.3302 -0.4318)
						)
						(arc
							(start 0.3302 -0.4318)
							(mid 0.402042 -0.402042)
							(end 0.4318 -0.3302)
						)
						(arc
							(start 0.4318 0.3302)
							(mid 0.402042 0.402042)
							(end 0.3302 0.4318)
						)
					)
					(width 0)
					(fill yes)
				)
			)
		)
	)
	(footprint ""
		(layer "B.Cu")
		(at 184.421272 -9.119108 90)
		(property "Reference" "C22W6"
			(at 0 0 90)
			(layer "B.SilkS")
			(hide yes)
			(effects
				(font
					(size 1.27 1.27)
				)
				(justify mirror)
			)
		)
		(property "Value" "*"
			(at 0.0762 -6.2357 90)
			(unlocked yes)
			(layer "B.Fab")
			(hide yes)
			(effects
				(font
					(size 1.27 1.016)
					(thickness 0.1524)
				)
				(justify mirror)
			)
		)
		(property "Device Type" "SC22U16V5MX-4-GP_SMD-BCG5-SC22A"
			(at 0.0762 -8.2677 90)
			(unlocked yes)
			(layer "B.Fab")
			(hide yes)
			(effects
				(font
					(size 1.27 1.016)
					(thickness 0.1524)
				)
				(justify mirror)
			)
		)
		(duplicate_pad_numbers_are_jumpers no)
		(fp_line
			(start -0.635 0)
			(end 0.635 0)
			(stroke
				(width 0.508)
				(type default)
			)
			(layer "B.SilkS")
		)
		(fp_rect
			(start 0.9652 1.778)
			(end -0.9652 -1.778)
			(stroke
				(width 0)
				(type default)
			)
			(fill no)
			(layer "B.CrtYd")
		)
		(fp_poly
			(pts
				(xy 0.9652 -1.778) (xy -0.9652 -1.778) (xy -0.9652 1.778) (xy 0.9652 1.778)
			)
			(stroke
				(width 0)
				(type default)
			)
			(fill no)
			(layer "B.Fab")
		)
		(pad "1" smd rect
			(at 0 -0.9652 270)
			(size 1.397 1.143)
			(layers "B.Cu" "B.Mask" "B.Paste")
			(net "VR_FET_SW_P12V_STBY_PVPP_GHJ")
		)
		(pad "2" smd rect
			(at 0 0.9652 270)
			(size 1.397 1.143)
			(layers "B.Cu" "B.Mask" "B.Paste")
			(net "GND")
		)
	)
	(footprint ""
		(layer "B.Cu")
		(at 342.642952 -89.300558 180)
		(property "Reference" "C3N39"
			(at 0 0 0)
			(layer "B.SilkS")
			(hide yes)
			(effects
				(font
					(size 1.27 1.27)
				)
				(justify mirror)
			)
		)
		(property "Value" ""
			(at 0 0 0)
			(layer "B.Fab")
			(effects
				(font
					(size 1.27 1.27)
				)
				(justify mirror)
			)
		)
		(duplicate_pad_numbers_are_jumpers no)
		(fp_poly
			(pts
				(xy -0.3048 -0.1016) (xy -0.3048 0.9906) (xy 0.3048 0.9906) (xy 0.3048 -0.1016)
			)
			(stroke
				(width 0)
				(type default)
			)
			(fill no)
			(layer "B.CrtYd")
		)
		(fp_line
			(start 0.3048 0.9906)
			(end -0.3048 0.9906)
			(stroke
				(width 0.1)
				(type default)
			)
			(layer "B.Fab")
		)
		(fp_line
			(start 0.3048 -0.1016)
			(end 0.3048 0.9906)
			(stroke
				(width 0.1)
				(type default)
			)
			(layer "B.Fab")
		)
		(fp_line
			(start -0.3048 0.9906)
			(end -0.3048 -0.1016)
			(stroke
				(width 0.1)
				(type default)
			)
			(layer "B.Fab")
		)
		(fp_line
			(start -0.3048 -0.1016)
			(end 0.3048 -0.1016)
			(stroke
				(width 0.1)
				(type default)
			)
			(layer "B.Fab")
		)
		(pad "1" smd rect
			(at 0 0)
			(size 0.508 0.508)
			(layers "B.Cu" "B.Mask" "B.Paste")
			(net "VR_PVCCIO_CPU0_AVSP")
		)
		(pad "2" smd rect
			(at 0 0.889)
			(size 0.508 0.508)
			(layers "B.Cu" "B.Mask" "B.Paste")
			(net "VSENSE_PVCCIO_CPU0_AVSN")
		)
		(zone
			(layer "B.Cu")
			(hatch none 0.5)
			(connect_pads
				(clearance 0)
			)
			(min_thickness 0.25)
			(keepout
				(tracks not_allowed)
				(vias allowed)
				(pads allowed)
				(copperpour not_allowed)
				(footprints allowed)
			)
			(placement
				(enabled no)
				(sheetname "")
			)
			(fill
				(thermal_gap 0.5)
				(thermal_bridge_width 0.5)
				(island_removal_mode 0)
			)
			(polygon
				(pts
					(xy 342.388952 -89.935558) (xy 342.896952 -89.935558) (xy 342.896952 -89.554558) (xy 342.388952 -89.554558)
				)
			)
		)
		(zone
			(layer "B.Cu")
			(hatch none 0.5)
			(connect_pads
				(clearance 0)
			)
			(min_thickness 0.25)
			(keepout
				(tracks allowed)
				(vias not_allowed)
				(pads allowed)
				(copperpour not_allowed)
				(footprints allowed)
			)
			(placement
				(enabled no)
				(sheetname "")
			)
			(fill
				(thermal_gap 0.5)
				(thermal_bridge_width 0.5)
				(island_removal_mode 0)
			)
			(polygon
				(pts
					(xy 342.388952 -89.554558) (xy 342.896952 -89.554558) (xy 342.896952 -89.935558) (xy 342.388952 -89.935558)
				)
			)
		)
	)
)
